# S9S_MB_2U (Grand Teton) — schematic netlist excerpt (pin names and nets, part order shuffled) for the footprints in the layout excerpt that follows; sources: Cadence DE-HDL packaged netlist, KiCad conversion of 03242023_DA0F0TMBIJ0_F0T_Motherboard_J_brd_V01_OCP.brd

C72  Q_CAP  2.2UF 6.3V 20% X6S  pkg C0402  page 113 : A = P3V3_AUX ; B = GND
C92  Q_CAP  10UF 16V 10% X6S  pkg C0805  page 107 : A = P12V_S3_AUX_CPU1_NVDIMM ; B = GND
C1903  Q_CAP  0.01UF 50V 10% X7R  pkg C0402  page 217 : A = VCC_PLD_CORE ; B = GND

(kicad_pcb
	(version 20260206)
	(generator "pcbnew")
	(generator_version "10.0")
	(general
		(thickness 1.6)
		(legacy_teardrops no)
	)
	(paper "A4")
	(title_block
		(title "03242023_DA0F0TMBIJ0_F0T_Motherboard_J_brd_V01_OCP.brd")
		(comment 1 "Grand Teton / footprints 5825-5827 of 6105")
	)
	(layers
		(0 "F.Cu" signal "TOP")
		(4 "In1.Cu" signal "GND")
		(6 "In2.Cu" signal "IN1")
		(8 "In3.Cu" signal "GND1")
		(10 "In4.Cu" signal "IN2")
		(12 "In5.Cu" signal "GND2")
		(14 "In6.Cu" signal "IN3")
		(16 "In7.Cu" signal "GND3")
		(18 "In8.Cu" signal "VCC")
		(20 "In9.Cu" signal "VCC1")
		(22 "In10.Cu" signal "GND4")
		(24 "In11.Cu" signal "IN4")
		(26 "In12.Cu" signal "GND5")
		(28 "In13.Cu" signal "IN5")
		(30 "In14.Cu" signal "GND6")
		(32 "In15.Cu" signal "IN6")
		(34 "In16.Cu" signal "GND7")
		(2 "B.Cu" signal "BOTTOM")
		(9 "F.Adhes" user "F.Adhesive")
		(11 "B.Adhes" user "B.Adhesive")
		(13 "F.Paste" user "Package Geometry/Pastemask Top")
		(15 "B.Paste" user "Package Geometry/Pastemask Bottom")
		(5 "F.SilkS" user "Ref Des/Silkscreen Top")
		(7 "B.SilkS" user "Ref Des/Silkscreen Bottom")
		(1 "F.Mask" user "Board Geometry/Soldermask Top")
		(3 "B.Mask" user "Board Geometry/Soldermask Bottom")
		(17 "Dwgs.User" user "User.Drawings")
		(19 "Cmts.User" user "User.Comments")
		(21 "Eco1.User" user "User.Eco1")
		(23 "Eco2.User" user "User.Eco2")
		(25 "Edge.Cuts" user "Board Geometry/Outline")
		(27 "Margin" user)
		(31 "F.CrtYd" user "Package Geometry/Place Bound Top")
		(29 "B.CrtYd" user "Package Geometry/Place Bound Bottom")
		(35 "F.Fab" user "Ref Des/Assembly Top")
		(33 "B.Fab" user "Ref Des/Assembly Bottom")
	)
	(footprint ""
		(layer "B.Cu")
		(at 204.088746 -319.268856 180)
		(property "Reference" "C72"
			(at 0 0 0)
			(layer "B.SilkS")
			(hide yes)
			(effects
				(font
					(size 1.27 1.27)
				)
				(justify mirror)
			)
		)
		(property "Value" ""
			(at 0 0 0)
			(layer "B.Fab")
			(effects
				(font
					(size 1.27 1.27)
				)
				(justify mirror)
			)
		)
		(duplicate_pad_numbers_are_jumpers no)
		(fp_line
			(start 0.7874 0.4064)
			(end 0.7874 -0.4064)
			(stroke
				(width 0.1524)
				(type default)
			)
			(layer "B.SilkS")
		)
		(fp_line
			(start 0.7874 -0.4064)
			(end -0.7874 -0.4064)
			(stroke
				(width 0.1524)
				(type default)
			)
			(layer "B.SilkS")
		)
		(fp_line
			(start -0.7874 0.4064)
			(end 0.7874 0.4064)
			(stroke
				(width 0.1524)
				(type default)
			)
			(layer "B.SilkS")
		)
		(fp_line
			(start -0.7874 -0.4064)
			(end -0.7874 0.4064)
			(stroke
				(width 0.1524)
				(type default)
			)
			(layer "B.SilkS")
		)
		(fp_line
			(start 0.67945 0.3048)
			(end 0.67945 -0.305054)
			(stroke
				(width 0.1)
				(type default)
			)
			(layer "B.Fab")
		)
		(fp_line
			(start 0.67945 -0.305054)
			(end 0.12065 -0.305054)
			(stroke
				(width 0.1)
				(type default)
			)
			(layer "B.Fab")
		)
		(fp_line
			(start 0.12065 0.3048)
			(end 0.67945 0.3048)
			(stroke
				(width 0.1)
				(type default)
			)
			(layer "B.Fab")
		)
		(fp_line
			(start 0.12065 0.2794)
			(end 0.12065 0.3048)
			(stroke
				(width 0.1)
				(type default)
			)
			(layer "B.Fab")
		)
		(fp_line
			(start 0.12065 -0.2794)
			(end -0.12065 -0.2794)
			(stroke
				(width 0.1)
				(type default)
			)
			(layer "B.Fab")
		)
		(fp_line
			(start 0.12065 -0.305054)
			(end 0.12065 -0.2794)
			(stroke
				(width 0.1)
				(type default)
			)
			(layer "B.Fab")
		)
		(fp_line
			(start -0.120396 0.3048)
			(end -0.120396 0.2794)
			(stroke
				(width 0.1)
				(type default)
			)
			(layer "B.Fab")
		)
		(fp_line
			(start -0.120396 0.2794)
			(end 0.12065 0.2794)
			(stroke
				(width 0.1)
				(type default)
			)
			(layer "B.Fab")
		)
		(fp_line
			(start -0.12065 -0.2794)
			(end -0.12065 -0.3048)
			(stroke
				(width 0.1)
				(type default)
			)
			(layer "B.Fab")
		)
		(fp_line
			(start -0.12065 -0.3048)
			(end -0.67945 -0.3048)
			(stroke
				(width 0.1)
				(type default)
			)
			(layer "B.Fab")
		)
		(fp_line
			(start -0.67945 0.3048)
			(end -0.120396 0.3048)
			(stroke
				(width 0.1)
				(type default)
			)
			(layer "B.Fab")
		)
		(fp_line
			(start -0.67945 -0.3048)
			(end -0.67945 0.3048)
			(stroke
				(width 0.1)
				(type default)
			)
			(layer "B.Fab")
		)
		(pad "1" smd circle
			(at 0.40005 0)
			(size 0 0)
			(layers "B.Cu" "B.Mask" "B.Paste")
			(net "P3V3_AUX")
		)
		(pad "2" smd circle
			(at -0.40005 0)
			(size 0 0)
			(layers "B.Cu" "B.Mask" "B.Paste")
			(net "GND")
		)
	)
	(footprint ""
		(layer "B.Cu")
		(at 162.889946 -321.554856 -90)
		(property "Reference" "C92"
			(at 0 0 90)
			(layer "B.SilkS")
			(hide yes)
			(effects
				(font
					(size 1.27 1.27)
				)
				(justify mirror)
			)
		)
		(property "Value" ""
			(at 0 0 90)
			(layer "B.Fab")
			(effects
				(font
					(size 1.27 1.27)
				)
				(justify mirror)
			)
		)
		(duplicate_pad_numbers_are_jumpers no)
		(fp_line
			(start -1.524 0.762)
			(end 1.524 0.762)
			(stroke
				(width 0.1524)
				(type default)
			)
			(layer "B.SilkS")
		)
		(fp_line
			(start 1.524 0.762)
			(end 1.524 -0.762)
			(stroke
				(width 0.1524)
				(type default)
			)
			(layer "B.SilkS")
		)
		(fp_line
			(start -1.524 -0.762)
			(end -1.524 0.762)
			(stroke
				(width 0.1524)
				(type default)
			)
			(layer "B.SilkS")
		)
		(fp_line
			(start 1.524 -0.762)
			(end -1.524 -0.762)
			(stroke
				(width 0.1524)
				(type default)
			)
			(layer "B.SilkS")
		)
		(fp_line
			(start -1.1049 0.724916)
			(end -1.1049 -0.724916)
			(stroke
				(width 0.1)
				(type default)
			)
			(layer "B.Fab")
		)
		(fp_line
			(start 1.1049 0.724916)
			(end -1.1049 0.724916)
			(stroke
				(width 0.1)
				(type default)
			)
			(layer "B.Fab")
		)
		(fp_line
			(start -1.1049 -0.724916)
			(end 1.1049 -0.724916)
			(stroke
				(width 0.1)
				(type default)
			)
			(layer "B.Fab")
		)
		(fp_line
			(start 1.1049 -0.724916)
			(end 1.1049 0.724916)
			(stroke
				(width 0.1)
				(type default)
			)
			(layer "B.Fab")
		)
		(pad "1" smd rect
			(at 0.889 0 270)
			(size 1.016 1.27)
			(layers "B.Cu" "B.Mask" "B.Paste")
			(net "P12V_S3_AUX_CPU1_NVDIMM")
		)
		(pad "2" smd rect
			(at -0.889 0 270)
			(size 1.016 1.27)
			(layers "B.Cu" "B.Mask" "B.Paste")
			(net "GND")
		)
	)
	(footprint ""
		(layer "B.Cu")
		(at 176.955704 -112.175544)
		(property "Reference" "C1903"
			(at 0 0 0)
			(layer "B.SilkS")
			(hide yes)
			(effects
				(font
					(size 1.27 1.27)
				)
				(justify mirror)
			)
		)
		(property "Value" ""
			(at 0 0 0)
			(layer "B.Fab")
			(effects
				(font
					(size 1.27 1.27)
				)
				(justify mirror)
			)
		)
		(duplicate_pad_numbers_are_jumpers no)
		(fp_line
			(start -0.69215 -0.2921)
			(end -0.69215 0.2921)
			(stroke
				(width 0.1524)
				(type default)
			)
			(layer "B.SilkS")
		)
		(fp_line
			(start -0.69215 0.2921)
			(end 0.69215 0.2921)
			(stroke
				(width 0.1524)
				(type default)
			)
			(layer "B.SilkS")
		)
		(fp_line
			(start 0.69215 -0.2921)
			(end -0.69215 -0.2921)
			(stroke
				(width 0.1524)
				(type default)
			)
			(layer "B.SilkS")
		)
		(fp_line
			(start 0.69215 0.2921)
			(end 0.69215 -0.2921)
			(stroke
				(width 0.1524)
				(type default)
			)
			(layer "B.SilkS")
		)
		(fp_line
			(start -0.51435 -0.2794)
			(end -0.51435 0.2794)
			(stroke
				(width 0.1)
				(type default)
			)
			(layer "B.Fab")
		)
		(fp_line
			(start -0.51435 0.2794)
			(end 0.51435 0.2794)
			(stroke
				(width 0.1)
				(type default)
			)
			(layer "B.Fab")
		)
		(fp_line
			(start 0.51435 -0.2794)
			(end -0.51435 -0.2794)
			(stroke
				(width 0.1)
				(type default)
			)
			(layer "B.Fab")
		)
		(fp_line
			(start 0.51435 0.2794)
			(end 0.51435 -0.2794)
			(stroke
				(width 0.1)
				(type default)
			)
			(layer "B.Fab")
		)
		(pad "1" smd circle
			(at 0.40005 0 180)
			(size 0 0)
			(layers "B.Cu" "B.Mask" "B.Paste")
			(net "VCC_PLD_CORE")
		)
		(pad "2" smd circle
			(at -0.40005 0 180)
			(size 0 0)
			(layers "B.Cu" "B.Mask" "B.Paste")
			(net "GND")
		)
		(zone
			(layer "B.Cu")
			(hatch none 0.5)
			(connect_pads
				(clearance 0)
			)
			(min_thickness 0.25)
			(keepout
				(tracks not_allowed)
				(vias allowed)
				(pads allowed)
				(copperpour not_allowed)
				(footprints allowed)
			)
			(placement
				(enabled no)
				(sheetname "")
			)
			(fill
				(thermal_gap 0.5)
				(thermal_bridge_width 0.5)
				(island_removal_mode 0)
			)
			(polygon
				(pts
					(xy 177.146204 -112.087914) (xy 177.054764 -112.029748) (xy 176.855374 -112.029748) (xy 176.765204 -112.087914)
					(xy 176.765204 -112.263174) (xy 176.855374 -112.321594) (xy 177.054764 -112.321594) (xy 177.146204 -112.263428)
				)
			)
		)
	)
)
